# S9S_MB_2U (Grand Teton) — schematic netlist excerpt (pin names and nets, part order shuffled) for the footprints in the layout excerpt that follows; sources: Cadence DE-HDL packaged netlist, KiCad conversion of 03242023_DA0F0TMBIJ0_F0T_Motherboard_J_brd_V01_OCP.brd

J27  SCONN288_ADR50017P130CC  SCONN288_ADR50017-P130CC IO  pkg DDR288S_1-1VXB  page 108
  VIN_BULK0  = P12V_S3_AUX_CPU1_NVDIMM
  RFU0  = TP_CHF_CPU1_DIMM1_FRU_0
  VIN_MGMT  = P3V3_AUX
  HSCL  = I3C_SPD_DDREFGH_CPU1_LVC1_SCL_2
  HSDA  = I3C_SPD_DDREFGH_CPU1_LVC1_SDA
  VSS0  = GND
  DQ0_A  = M_F_CPU1_SA_DQ<0>
  VSS1  = GND
  DQ1_A  = M_F_CPU1_SA_DQ<1>
  VSS2  = GND
  DQS0_A_T  = M_F_CPU1_SA_DQS_DP<0>
  DQS0_A_C  = M_F_CPU1_SA_DQS_DN<0>
  VSS3  = GND
  DQ4_A  = M_F_CPU1_SA_DQ<4>
  VSS4  = GND
  DQ5_A  = M_F_CPU1_SA_DQ<5>
  VSS5  = GND
  DQ8_A  = M_F_CPU1_SA_DQ<8>
  VSS6  = GND
  DQ9_A  = M_F_CPU1_SA_DQ<9>
  VSS7  = GND
  DQS1_A_T  = M_F_CPU1_SA_DQS_DP<1>
  DQS1_A_C  = M_F_CPU1_SA_DQS_DN<1>
  VSS8  = GND
  DQ12_A  = M_F_CPU1_SA_DQ<12>
  VSS9  = GND
  DQ13_A  = M_F_CPU1_SA_DQ<13>
  VSS10  = GND
  DQ16_A  = M_F_CPU1_SA_DQ<16>
  VSS11  = GND
  DQ17_A  = M_F_CPU1_SA_DQ<17>
  VSS12  = GND
  DQS2_A_T  = M_F_CPU1_SA_DQS_DP<2>
  DQS2_A_C  = M_F_CPU1_SA_DQS_DN<2>
  VSS13  = GND
  DQ20_A  = M_F_CPU1_SA_DQ<20>
  VSS14  = GND
  DQ21_A  = M_F_CPU1_SA_DQ<21>
  VSS15  = GND
  DQ24_A  = M_F_CPU1_SA_DQ<24>
  VSS16  = GND
  DQ25_A  = M_F_CPU1_SA_DQ<25>
  VSS17  = GND
  DQS3_A_T  = M_F_CPU1_SA_DQS_DP<3>
  DQS3_A_C  = M_F_CPU1_SA_DQS_DN<3>
  VSS18  = GND
  DQ28_A  = M_F_CPU1_SA_DQ<28>
  VSS19  = GND
  DQ29_A  = M_F_CPU1_SA_DQ<29>
  VSS20  = GND
  CB0_A  = M_F_CPU1_SA_CB<0>
  VSS21  = GND
  CB1_A  = M_F_CPU1_SA_CB<1>
  VSS22  = GND
  DQS4_A_T  = M_F_CPU1_SA_DQS_DP<4>
  DQS4_A_C  = M_F_CPU1_SA_DQS_DN<4>
  VSS23  = GND
  CB4_A  = M_F_CPU1_SA_CB<4>
  VSS24  = GND
  CB5_A  = M_F_CPU1_SA_CB<5>
  VSS25  = GND
  ALERT_N  = M_F_CPU1_ALERT_N
  VSS26  = GND
  CS0_A_N  = M_F_CPU1_SA_CS_N<0>
  VSS27  = GND
  CA0_A  = M_F_CPU1_SA_CA<0>
  VSS28  = GND
  CA2_A  = M_F_CPU1_SA_CA<2>
  VSS29  = GND
  CA4_A  = M_F_CPU1_SA_CA<4>
  VSS30  = GND
  CA6_A  = M_F_CPU1_SA_CA<6>
  VSS31  = GND
  PAR_A  = M_F_CPU1_SA_PAR
  VSS32  = GND
  CA0_B  = M_F_CPU1_SB_CA<0>
  VSS33  = GND
  CA2_B  = M_F_CPU1_SB_CA<2>
  VSS34  = GND
  CA4_B  = M_F_CPU1_SB_CA<4>
  VSS35  = GND
  CA6_B  = M_F_CPU1_SB_CA<6>
  VSS36  = GND
  CS0_B_N  = M_F_CPU1_SB_CS_N<0>
  VSS37  = GND
  \lbd||rsp_a_n\  = M_F_CPU1_SA_RSP<0>
  \lbs||rsp_b_n\  = M_F_CPU1_SB_RSP<0>
  VSS38  = GND
  CB4_B  = M_F_CPU1_SB_CB<4>
  VSS39  = GND
  CB5_B  = M_F_CPU1_SB_CB<5>
  VSS40  = GND
  \dqs9_b_t||tdqs9_b_t||dbi4_b_n\  = M_F_CPU1_SB_DQS_DP<9>
  \dqs9_b_c||tdqs9_b_c\  = M_F_CPU1_SB_DQS_DN<9>
  VSS41  = GND
  CB0_B  = M_F_CPU1_SB_CB<0>
  VSS42  = GND
  CB1_B  = M_F_CPU1_SB_CB<1>
  VSS43  = GND
  DQ0_B  = M_F_CPU1_SB_DQ<0>
  VSS44  = GND
  DQ1_B  = M_F_CPU1_SB_DQ<1>
  VSS45  = GND
  DQS0_B_T  = M_F_CPU1_SB_DQS_DP<0>
  DQS0_B_C  = M_F_CPU1_SB_DQS_DN<0>
  VSS46  = GND
  DQ4_B  = M_F_CPU1_SB_DQ<4>
  VSS47  = GND
  DQ5_B  = M_F_CPU1_SB_DQ<5>
  VSS48  = GND
  DQ8_B  = M_F_CPU1_SB_DQ<8>
  VSS49  = GND
  DQ9_B  = M_F_CPU1_SB_DQ<9>
  VSS50  = GND
  DQS1_B_T  = M_F_CPU1_SB_DQS_DP<1>
  DQS1_B_C  = M_F_CPU1_SB_DQS_DN<1>
  VSS51  = GND
  DQ12_B  = M_F_CPU1_SB_DQ<12>
  VSS52  = GND
  DQ13_B  = M_F_CPU1_SB_DQ<13>
  VSS53  = GND
  DQ16_B  = M_F_CPU1_SB_DQ<16>
  VSS54  = GND
  DQ17_B  = M_F_CPU1_SB_DQ<17>
  VSS55  = GND
  DQS2_B_T  = M_F_CPU1_SB_DQS_DP<2>
  DQS2_B_C  = M_F_CPU1_SB_DQS_DN<2>
  VSS56  = GND
  DQ20_B  = M_F_CPU1_SB_DQ<20>
  VSS57  = GND
  DQ21_B  = M_F_CPU1_SB_DQ<21>
  VSS58  = GND
  DQ24_B  = M_F_CPU1_SB_DQ<24>
  VSS59  = GND
  DQ25_B  = M_F_CPU1_SB_DQ<25>
  VSS60  = GND
  DQS3_B_T  = M_F_CPU1_SB_DQS_DP<3>
  DQS3_B_C  = M_F_CPU1_SB_DQS_DN<3>
  VSS61  = GND
  DQ28_B  = M_F_CPU1_SB_DQ<28>
  VSS62  = GND
  DQ29_B  = M_F_CPU1_SB_DQ<29>
  VSS63  = GND
  RFU1  = TP_CHF_CPU1_DIMM1_FRU_1
  VIN_BULK1  = P12V_S3_AUX_CPU1_NVDIMM
  VIN_BULK2  = P12V_S3_AUX_CPU1_NVDIMM
  \pwr_good||fail_n\  = PWRGD_CHF_CPU1_DIMM1
  HSA  = PD_CHF_CPU1_DIMM1_SAA
  RFU2  = TP_CHF_CPU1_DIMM1_FRU_2
  RFU3  = TP_CHF_CPU1_DIMM1_FRU_3
  VSS64  = GND
  DQ2_A  = M_F_CPU1_SA_DQ<2>
  VSS65  = GND
  DQ3_A  = M_F_CPU1_SA_DQ<3>
  VSS66  = GND
  \dqs5_a_c||tdqs5_a_c||dqs5_a_t||tdqs5_a_t\  = M_F_CPU1_SA_DQS_DN<5>
  \dqs5_a_t||tdqs5_a_t\  = M_F_CPU1_SA_DQS_DP<5>
  VSS67  = GND
  DQ6_A  = M_F_CPU1_SA_DQ<6>
  VSS68  = GND
  DQ7_A  = M_F_CPU1_SA_DQ<7>
  VSS69  = GND
  DQ10_A  = M_F_CPU1_SA_DQ<10>
  VSS70  = GND
  DQ11_A  = M_F_CPU1_SA_DQ<11>
  VSS71  = GND
  \dqs6_a_c||tdqs6_a_c||dqs6_a_t||tdqs6_a_t\  = M_F_CPU1_SA_DQS_DN<6>
  \dqs6_a_t||tdqs6_a_t\  = M_F_CPU1_SA_DQS_DP<6>
  VSS72  = GND
  DQ14_A  = M_F_CPU1_SA_DQ<14>
  VSS73  = GND
  DQ15_A  = M_F_CPU1_SA_DQ<15>
  VSS74  = GND
  DQ18_A  = M_F_CPU1_SA_DQ<18>
  VSS75  = GND
  DQ19_A  = M_F_CPU1_SA_DQ<19>
  VSS76  = GND
  \dqs7_a_c||tdqs7_a_c\  = M_F_CPU1_SA_DQS_DN<7>
  \dqs7_a_t||tdqs7_a_t\  = M_F_CPU1_SA_DQS_DP<7>
  VSS77  = GND
  DQ22_A  = M_F_CPU1_SA_DQ<22>
  VSS78  = GND
  DQ23_A  = M_F_CPU1_SA_DQ<23>
  VSS79  = GND
  DQ26_A  = M_F_CPU1_SA_DQ<26>
  VSS80  = GND
  DQ27_A  = M_F_CPU1_SA_DQ<27>
  VSS81  = GND
  \dqs8_a_c||tdqs8_a_c\  = M_F_CPU1_SA_DQS_DN<8>
  \dqs8_a_t||tdqs8_a_t\  = M_F_CPU1_SA_DQS_DP<8>
  VSS82  = GND
  DQ30_A  = M_F_CPU1_SA_DQ<30>
  VSS83  = GND
  DQ31_A  = M_F_CPU1_SA_DQ<31>
  VSS84  = GND
  CB2_A  = M_F_CPU1_SA_CB<2>
  VSS85  = GND
  CB3_A  = M_F_CPU1_SA_CB<3>
  VSS86  = GND
  \dqs9_a_c||tdqs9_a_c\  = M_F_CPU1_SA_DQS_DN<9>
  \dqs9_a_t||tdqs9_a_t\  = M_F_CPU1_SA_DQS_DP<9>
  VSS87  = GND
  CB6_A  = M_F_CPU1_SA_CB<6>
  VSS88  = GND
  CB7_A  = M_F_CPU1_SA_CB<7>
  VSS89  = GND
  RESET_N  = RST_M_EF_CPU1_FPGA_N
  VSS90  = GND
  CS1_A_N  = M_F_CPU1_SA_CS_N<1>
  VSS91  = GND
  CA1_A  = M_F_CPU1_SA_CA<1>
  VSS92  = GND
  CA3_A  = M_F_CPU1_SA_CA<3>
  VSS93  = GND
  CA5_A  = M_F_CPU1_SA_CA<5>
  VSS94  = GND
  CK_T  = M_F_CPU1_CLK_DP<0>
  CK_C  = M_F_CPU1_CLK_DN<0>
  VSS95  = GND
  RFU4  = TP_CHF_CPU1_DIMM1_FRU_4
  CA1_B  = M_F_CPU1_SB_CA<1>
  VSS96  = GND
  CA3_B  = M_F_CPU1_SB_CA<3>
  VSS97  = GND
  CA5_B  = M_F_CPU1_SB_CA<5>
  VSS98  = GND
  PAR_B  = M_F_CPU1_SB_PAR
  VSS99  = GND
  CS1_B_N  = M_F_CPU1_SB_CS_N<1>
  VSS100  = GND
  RFU5  = TP_CHF_CPU1_DIMM1_FRU_5
  RFU6  = TP_CHF_CPU1_DIMM1_FRU_6
  VSS101  = GND
  CB6_B  = M_F_CPU1_SB_CB<6>
  VSS102  = GND
  CB7_B  = M_F_CPU1_SB_CB<7>
  VSS103  = GND
  DQS4_B_C  = M_F_CPU1_SB_DQS_DN<4>
  DQS4_B_T  = M_F_CPU1_SB_DQS_DP<4>
  VSS104  = GND
  CB2_B  = M_F_CPU1_SB_CB<2>
  VSS105  = GND
  CB3_B  = M_F_CPU1_SB_CB<3>
  VSS106  = GND
  DQ2_B  = M_F_CPU1_SB_DQ<2>
  VSS107  = GND
  DQ3_B  = M_F_CPU1_SB_DQ<3>
  VSS108  = GND
  \dqs5_b_c||tdqs5_b_c\  = M_F_CPU1_SB_DQS_DN<5>
  \dqs5_b_t||tdqs5_b_t\  = M_F_CPU1_SB_DQS_DP<5>
  VSS109  = GND
  DQ6_B  = M_F_CPU1_SB_DQ<6>
  VSS110  = GND
  DQ7_B  = M_F_CPU1_SB_DQ<7>
  VSS111  = GND
  DQ10_B  = M_F_CPU1_SB_DQ<10>
  VSS112  = GND
  DQ11_B  = M_F_CPU1_SB_DQ<11>
  VSS113  = GND
  \dqs6_b_c||tdqs6_b_c\  = M_F_CPU1_SB_DQS_DN<6>
  \dqs6_b_t||tdqs6_b_t\  = M_F_CPU1_SB_DQS_DP<6>
  VSS114  = GND
  DQ14_B  = M_F_CPU1_SB_DQ<14>
  VSS115  = GND
  DQ15_B  = M_F_CPU1_SB_DQ<15>
  VSS116  = GND
  DQ18_B  = M_F_CPU1_SB_DQ<18>
  VSS117  = GND
  DQ19_B  = M_F_CPU1_SB_DQ<19>
  VSS118  = GND
  \dqs7_b_c||tdqs7_b_c\  = M_F_CPU1_SB_DQS_DN<7>
  \dqs7_b_t||tdqs7_b_t\  = M_F_CPU1_SB_DQS_DP<7>
  VSS119  = GND
  DQ22_B  = M_F_CPU1_SB_DQ<22>
  VSS120  = GND
  DQ23_B  = M_F_CPU1_SB_DQ<23>
  VSS121  = GND
  DQ26_B  = M_F_CPU1_SB_DQ<26>
  VSS122  = GND
  DQ27_B  = M_F_CPU1_SB_DQ<27>
  VSS123  = GND
  \dqs8_b_c||tdqs8_b_c\  = M_F_CPU1_SB_DQS_DN<8>
  \dqs8_b_t||tdqs8_b_t\  = M_F_CPU1_SB_DQS_DP<8>
  VSS124  = GND
  DQ30_B  = M_F_CPU1_SB_DQ<30>
  VSS125  = GND
  DQ31_B  = M_F_CPU1_SB_DQ<31>
  VSS126  = GND
  G1  = GND
  G2  = GND
  G3  = GND

(kicad_pcb
	(version 20260206)
	(generator "pcbnew")
	(generator_version "10.0")
	(general
		(thickness 1.6)
		(legacy_teardrops no)
	)
	(paper "A4")
	(title_block
		(title "03242023_DA0F0TMBIJ0_F0T_Motherboard_J_brd_V01_OCP.brd")
		(comment 1 "Grand Teton / footprint 1301 of 6105 (J27), pads 46-91 of 291")
	)
	(layers
		(0 "F.Cu" signal "TOP")
		(4 "In1.Cu" signal "GND")
		(6 "In2.Cu" signal "IN1")
		(8 "In3.Cu" signal "GND1")
		(10 "In4.Cu" signal "IN2")
		(12 "In5.Cu" signal "GND2")
		(14 "In6.Cu" signal "IN3")
		(16 "In7.Cu" signal "GND3")
		(18 "In8.Cu" signal "VCC")
		(20 "In9.Cu" signal "VCC1")
		(22 "In10.Cu" signal "GND4")
		(24 "In11.Cu" signal "IN4")
		(26 "In12.Cu" signal "GND5")
		(28 "In13.Cu" signal "IN5")
		(30 "In14.Cu" signal "GND6")
		(32 "In15.Cu" signal "IN6")
		(34 "In16.Cu" signal "GND7")
		(2 "B.Cu" signal "BOTTOM")
		(9 "F.Adhes" user "F.Adhesive")
		(11 "B.Adhes" user "B.Adhesive")
		(13 "F.Paste" user "Package Geometry/Pastemask Top")
		(15 "B.Paste" user "Package Geometry/Pastemask Bottom")
		(5 "F.SilkS" user "Ref Des/Silkscreen Top")
		(7 "B.SilkS" user "Ref Des/Silkscreen Bottom")
		(1 "F.Mask" user "Board Geometry/Soldermask Top")
		(3 "B.Mask" user "Board Geometry/Soldermask Bottom")
		(17 "Dwgs.User" user "User.Drawings")
		(19 "Cmts.User" user "User.Comments")
		(21 "Eco1.User" user "User.Eco1")
		(23 "Eco2.User" user "User.Eco2")
		(25 "Edge.Cuts" user "Board Geometry/Outline")
		(27 "Margin" user)
		(31 "F.CrtYd" user "Package Geometry/Place Bound Top")
		(29 "B.CrtYd" user "Package Geometry/Place Bound Bottom")
		(35 "F.Fab" user "Ref Des/Assembly Top")
		(33 "B.Fab" user "Ref Des/Assembly Bottom")
	)
	(footprint ""
		(layer "F.Cu")
		(at 183.49468 -258.091686)
		(property "Reference" "J27"
			(at 2.19456 -81.755488 0)
			(unlocked yes)
			(layer "F.SilkS")
			(effects
				(font
					(size 0.7874 0.5842)
					(thickness 0.1524)
				)
				(justify left)
			)
		)
		(property "Value" ""
			(at 0 0 0)
			(layer "F.Fab")
			(effects
				(font
					(size 1.27 1.27)
				)
			)
		)
		(duplicate_pad_numbers_are_jumpers no)
		(pad "46" smd rect
			(at -2.050034 -25.07488 270)
			(size 0.519938 1.4986)
			(layers "F.Cu" "F.Mask" "F.Paste")
			(net "GND")
		)
		(pad "47" smd rect
			(at -2.050034 -24.224996 270)
			(size 0.519938 1.4986)
			(layers "F.Cu" "F.Mask" "F.Paste")
			(net "M_F_CPU1_SA_DQ<28>")
		)
		(pad "48" smd rect
			(at -2.050034 -23.375112 270)
			(size 0.519938 1.4986)
			(layers "F.Cu" "F.Mask" "F.Paste")
			(net "GND")
		)
		(pad "49" smd rect
			(at -2.050034 -22.524974 270)
			(size 0.519938 1.4986)
			(layers "F.Cu" "F.Mask" "F.Paste")
			(net "M_F_CPU1_SA_DQ<29>")
		)
		(pad "50" smd rect
			(at -2.050034 -21.67509 270)
			(size 0.519938 1.4986)
			(layers "F.Cu" "F.Mask" "F.Paste")
			(net "GND")
		)
		(pad "51" smd rect
			(at -2.050034 -20.824952 270)
			(size 0.519938 1.4986)
			(layers "F.Cu" "F.Mask" "F.Paste")
			(net "M_F_CPU1_SA_CB<0>")
		)
		(pad "52" smd rect
			(at -2.050034 -19.975068 270)
			(size 0.519938 1.4986)
			(layers "F.Cu" "F.Mask" "F.Paste")
			(net "GND")
		)
		(pad "53" smd rect
			(at -2.050034 -19.12493 270)
			(size 0.519938 1.4986)
			(layers "F.Cu" "F.Mask" "F.Paste")
			(net "M_F_CPU1_SA_CB<1>")
		)
		(pad "54" smd rect
			(at -2.050034 -18.275046 270)
			(size 0.519938 1.4986)
			(layers "F.Cu" "F.Mask" "F.Paste")
			(net "GND")
		)
		(pad "55" smd rect
			(at -2.050034 -17.424908 270)
			(size 0.519938 1.4986)
			(layers "F.Cu" "F.Mask" "F.Paste")
			(net "M_F_CPU1_SA_DQS_DP<4>")
		)
		(pad "56" smd rect
			(at -2.050034 -16.575024 270)
			(size 0.519938 1.4986)
			(layers "F.Cu" "F.Mask" "F.Paste")
			(net "M_F_CPU1_SA_DQS_DN<4>")
		)
		(pad "57" smd rect
			(at -2.050034 -15.724886 270)
			(size 0.519938 1.4986)
			(layers "F.Cu" "F.Mask" "F.Paste")
			(net "GND")
		)
		(pad "58" smd rect
			(at -2.050034 -14.875002 270)
			(size 0.519938 1.4986)
			(layers "F.Cu" "F.Mask" "F.Paste")
			(net "M_F_CPU1_SA_CB<4>")
		)
		(pad "59" smd rect
			(at -2.050034 -14.025118 270)
			(size 0.519938 1.4986)
			(layers "F.Cu" "F.Mask" "F.Paste")
			(net "GND")
		)
		(pad "60" smd rect
			(at -2.050034 -13.17498 270)
			(size 0.519938 1.4986)
			(layers "F.Cu" "F.Mask" "F.Paste")
			(net "M_F_CPU1_SA_CB<5>")
		)
		(pad "61" smd rect
			(at -2.050034 -12.325096 270)
			(size 0.519938 1.4986)
			(layers "F.Cu" "F.Mask" "F.Paste")
			(net "GND")
		)
		(pad "62" smd rect
			(at -2.050034 -11.474958 270)
			(size 0.519938 1.4986)
			(layers "F.Cu" "F.Mask" "F.Paste")
			(net "M_F_CPU1_ALERT_N")
		)
		(pad "63" smd rect
			(at -2.050034 -10.625074 270)
			(size 0.519938 1.4986)
			(layers "F.Cu" "F.Mask" "F.Paste")
			(net "GND")
		)
		(pad "64" smd rect
			(at -2.050034 -9.774936 270)
			(size 0.519938 1.4986)
			(layers "F.Cu" "F.Mask" "F.Paste")
			(net "M_F_CPU1_SA_CS_N<0>")
		)
		(pad "65" smd rect
			(at -2.050034 -8.925052 270)
			(size 0.519938 1.4986)
			(layers "F.Cu" "F.Mask" "F.Paste")
			(net "GND")
		)
		(pad "66" smd rect
			(at -2.050034 -8.074914 270)
			(size 0.519938 1.4986)
			(layers "F.Cu" "F.Mask" "F.Paste")
			(net "M_F_CPU1_SA_CA<0>")
		)
		(pad "67" smd rect
			(at -2.050034 -7.22503 270)
			(size 0.519938 1.4986)
			(layers "F.Cu" "F.Mask" "F.Paste")
			(net "GND")
		)
		(pad "68" smd rect
			(at -2.050034 -6.374892 270)
			(size 0.519938 1.4986)
			(layers "F.Cu" "F.Mask" "F.Paste")
			(net "M_F_CPU1_SA_CA<2>")
		)
		(pad "69" smd rect
			(at -2.050034 -5.525008 270)
			(size 0.519938 1.4986)
			(layers "F.Cu" "F.Mask" "F.Paste")
			(net "GND")
		)
		(pad "70" smd rect
			(at -2.050034 -4.675124 270)
			(size 0.519938 1.4986)
			(layers "F.Cu" "F.Mask" "F.Paste")
			(net "M_F_CPU1_SA_CA<4>")
		)
		(pad "71" smd rect
			(at -2.050034 -3.824986 270)
			(size 0.519938 1.4986)
			(layers "F.Cu" "F.Mask" "F.Paste")
			(net "GND")
		)
		(pad "72" smd rect
			(at -2.050034 -2.975102 270)
			(size 0.519938 1.4986)
			(layers "F.Cu" "F.Mask" "F.Paste")
			(net "M_F_CPU1_SA_CA<6>")
		)
		(pad "73" smd rect
			(at -2.050034 -2.124964 270)
			(size 0.519938 1.4986)
			(layers "F.Cu" "F.Mask" "F.Paste")
			(net "GND")
		)
		(pad "74" smd rect
			(at -2.050034 -1.27508 270)
			(size 0.519938 1.4986)
			(layers "F.Cu" "F.Mask" "F.Paste")
			(net "M_F_CPU1_SA_PAR")
		)
		(pad "75" smd rect
			(at -2.050034 -0.424942 270)
			(size 0.519938 1.4986)
			(layers "F.Cu" "F.Mask" "F.Paste")
			(net "GND")
		)
		(pad "76" smd rect
			(at -2.050034 5.525008 270)
			(size 0.519938 1.4986)
			(layers "F.Cu" "F.Mask" "F.Paste")
			(net "M_F_CPU1_SB_CA<0>")
		)
		(pad "77" smd rect
			(at -2.050034 6.374892 270)
			(size 0.519938 1.4986)
			(layers "F.Cu" "F.Mask" "F.Paste")
			(net "GND")
		)
		(pad "78" smd rect
			(at -2.050034 7.22503 270)
			(size 0.519938 1.4986)
			(layers "F.Cu" "F.Mask" "F.Paste")
			(net "M_F_CPU1_SB_CA<2>")
		)
		(pad "79" smd rect
			(at -2.050034 8.074914 270)
			(size 0.519938 1.4986)
			(layers "F.Cu" "F.Mask" "F.Paste")
			(net "GND")
		)
		(pad "80" smd rect
			(at -2.050034 8.925052 270)
			(size 0.519938 1.4986)
			(layers "F.Cu" "F.Mask" "F.Paste")
			(net "M_F_CPU1_SB_CA<4>")
		)
		(pad "81" smd rect
			(at -2.050034 9.774936 270)
			(size 0.519938 1.4986)
			(layers "F.Cu" "F.Mask" "F.Paste")
			(net "GND")
		)
		(pad "82" smd rect
			(at -2.050034 10.625074 270)
			(size 0.519938 1.4986)
			(layers "F.Cu" "F.Mask" "F.Paste")
			(net "M_F_CPU1_SB_CA<6>")
		)
		(pad "83" smd rect
			(at -2.050034 11.474958 270)
			(size 0.519938 1.4986)
			(layers "F.Cu" "F.Mask" "F.Paste")
			(net "GND")
		)
		(pad "84" smd rect
			(at -2.050034 12.325096 270)
			(size 0.519938 1.4986)
			(layers "F.Cu" "F.Mask" "F.Paste")
			(net "M_F_CPU1_SB_CS_N<0>")
		)
		(pad "85" smd rect
			(at -2.050034 13.17498 270)
			(size 0.519938 1.4986)
			(layers "F.Cu" "F.Mask" "F.Paste")
			(net "GND")
		)
		(pad "86" smd rect
			(at -2.050034 14.025118 270)
			(size 0.519938 1.4986)
			(layers "F.Cu" "F.Mask" "F.Paste")
			(net "M_F_CPU1_SA_RSP<0>")
		)
		(pad "87" smd rect
			(at -2.050034 14.875002 270)
			(size 0.519938 1.4986)
			(layers "F.Cu" "F.Mask" "F.Paste")
			(net "M_F_CPU1_SB_RSP<0>")
		)
		(pad "88" smd rect
			(at -2.050034 15.724886 270)
			(size 0.519938 1.4986)
			(layers "F.Cu" "F.Mask" "F.Paste")
			(net "GND")
		)
		(pad "89" smd rect
			(at -2.050034 16.575024 270)
			(size 0.519938 1.4986)
			(layers "F.Cu" "F.Mask" "F.Paste")
			(net "M_F_CPU1_SB_CB<4>")
		)
		(pad "90" smd rect
			(at -2.050034 17.424908 270)
			(size 0.519938 1.4986)
			(layers "F.Cu" "F.Mask" "F.Paste")
			(net "GND")
		)
		(pad "91" smd rect
			(at -2.050034 18.275046 270)
			(size 0.519938 1.4986)
			(layers "F.Cu" "F.Mask" "F.Paste")
			(net "M_F_CPU1_SB_CB<5>")
		)
	)
)
